G04*
G04 #@! TF.GenerationSoftware,Altium Limited,Altium Designer,22.4.2 (48)*
G04*
G04 Layer_Color=32768*
%FSLAX25Y25*%
%MOIN*%
G70*
G04*
G04 #@! TF.SameCoordinates,446674BB-F454-490D-8607-5140536C8ADF*
G04*
G04*
G04 #@! TF.FilePolarity,Positive*
G04*
G01*
G75*
G36*
X345984Y-322753D02*
X326298D01*
Y-303067D01*
X345984D01*
Y-322753D01*
D02*
G37*
G36*
X346185Y-165408D02*
X326499D01*
Y-145722D01*
X346185D01*
Y-165408D01*
D02*
G37*
G36*
X542756Y-322764D02*
X523070D01*
Y-303079D01*
X542756D01*
Y-322764D01*
D02*
G37*
G36*
X542699Y-165591D02*
X523013D01*
Y-145905D01*
X542699D01*
Y-165591D01*
D02*
G37*
M02*
